(kicad_pcb
	(version 20260206)
	(generator "pcbnew")
	(generator_version "10.0")
	(general
		(thickness 1.6)
		(legacy_teardrops no)
	)
	(paper "A4")
	(title_block
		(title "baseboard — 13948-1b.1110WZS1818.brd")
		(comment 1 "Honey Badger (Wiwynn) / footprints 2037-2046 of 2523")
	)
	(layers
		(0 "F.Cu" signal "TOP")
		(4 "In1.Cu" signal "L2GND")
		(6 "In2.Cu" signal "L3")
		(8 "In3.Cu" signal "L4VCC")
		(10 "In4.Cu" signal "L5VCC")
		(12 "In5.Cu" signal "L6")
		(14 "In6.Cu" signal "L7GND")
		(2 "B.Cu" signal "BOTTOM")
		(9 "F.Adhes" user "F.Adhesive")
		(11 "B.Adhes" user "B.Adhesive")
		(13 "F.Paste" user "Package Geometry/Pastemask Top")
		(15 "B.Paste" user "Package Geometry/Pastemask Bottom")
		(5 "F.SilkS" user "Ref Des/Silkscreen Top")
		(7 "B.SilkS" user "Ref Des/Silkscreen Bottom")
		(1 "F.Mask" user "Board Geometry/Soldermask Top")
		(3 "B.Mask" user "Board Geometry/Soldermask Bottom")
		(17 "Dwgs.User" user "User.Drawings")
		(19 "Cmts.User" user "User.Comments")
		(21 "Eco1.User" user "User.Eco1")
		(23 "Eco2.User" user "User.Eco2")
		(25 "Edge.Cuts" user "Board Geometry/Outline")
		(27 "Margin" user)
		(31 "F.CrtYd" user "Package Geometry/Place Bound Top")
		(29 "B.CrtYd" user "Package Geometry/Place Bound Bottom")
		(35 "F.Fab" user "Ref Des/Assembly Top")
		(33 "B.Fab" user "Ref Des/Assembly Bottom")
	)
	(footprint ""
		(layer "B.Cu")
		(at 303.276 -178.562)
		(property "Reference" "TP162"
			(at 0 0 0)
			(layer "B.SilkS")
			(hide yes)
			(effects
				(font
					(size 1.27 1.27)
				)
				(justify mirror)
			)
		)
		(property "Value" "TPAD28"
			(at -0.0127 -1.8034 0)
			(unlocked yes)
			(layer "B.Fab")
			(hide yes)
			(effects
				(font
					(size 1.016 1.016)
					(thickness 0.1524)
				)
				(justify mirror)
			)
		)
		(property "Device Type" "TPAD28"
			(at -0.0127 -3.3274 0)
			(unlocked yes)
			(layer "B.Fab")
			(hide yes)
			(effects
				(font
					(size 1.016 1.016)
					(thickness 0.1524)
				)
				(justify mirror)
			)
		)
		(duplicate_pad_numbers_are_jumpers no)
		(fp_poly
			(pts
				(arc
					(start 0.3556 0)
					(mid -0.3556 0)
					(end 0.3556 0)
				)
			)
			(stroke
				(width 0)
				(type default)
			)
			(fill no)
			(layer "B.CrtYd")
		)
		(fp_poly
			(pts
				(arc
					(start 0.6096 0)
					(mid -0.6096 0)
					(end 0.6096 0)
				)
			)
			(stroke
				(width 0)
				(type default)
			)
			(fill no)
			(layer "B.Fab")
		)
		(pad "1" smd circle
			(at 0 0 180)
			(size 0.7112 0.7112)
			(layers "B.Cu" "B.Mask" "B.Paste")
			(net "TP_BMC_GPIOJ7")
		)
	)
	(footprint ""
		(layer "B.Cu")
		(at 89.67216 -51.435)
		(property "Reference" "STP18"
			(at 0 0 0)
			(layer "B.SilkS")
			(hide yes)
			(effects
				(font
					(size 1.27 1.27)
				)
				(justify mirror)
			)
		)
		(property "Value" "TPAD28"
			(at -0.0127 -1.8034 0)
			(unlocked yes)
			(layer "B.Fab")
			(hide yes)
			(effects
				(font
					(size 1.016 1.016)
					(thickness 0.1524)
				)
				(justify mirror)
			)
		)
		(property "Device Type" "TPAD28"
			(at -0.0127 -3.3274 0)
			(unlocked yes)
			(layer "B.Fab")
			(hide yes)
			(effects
				(font
					(size 1.016 1.016)
					(thickness 0.1524)
				)
				(justify mirror)
			)
		)
		(duplicate_pad_numbers_are_jumpers no)
		(fp_poly
			(pts
				(arc
					(start 0.3556 0)
					(mid -0.3556 0)
					(end 0.3556 0)
				)
			)
			(stroke
				(width 0)
				(type default)
			)
			(fill no)
			(layer "B.CrtYd")
		)
		(fp_poly
			(pts
				(arc
					(start 0.6096 0)
					(mid -0.6096 0)
					(end 0.6096 0)
				)
			)
			(stroke
				(width 0)
				(type default)
			)
			(fill no)
			(layer "B.Fab")
		)
		(pad "1" smd circle
			(at 0 0 180)
			(size 0.7112 0.7112)
			(layers "B.Cu" "B.Mask" "B.Paste")
			(net "SIO_LOAD_1")
		)
	)
	(footprint ""
		(layer "B.Cu")
		(at 124.21997 -100.33)
		(property "Reference" "SC1191"
			(at 0 0 0)
			(layer "B.SilkS")
			(hide yes)
			(effects
				(font
					(size 1.27 1.27)
				)
				(justify mirror)
			)
		)
		(property "Value" "SCD1U6D3V1KX-GP"
			(at 2.8321 -1.7399 0)
			(unlocked yes)
			(layer "B.Fab")
			(hide yes)
			(effects
				(font
					(size 1.016 1.016)
					(thickness 0.1524)
				)
				(justify mirror)
			)
		)
		(property "Device Type" "C0201H13"
			(at 2.8321 -3.2639 0)
			(unlocked yes)
			(layer "B.Fab")
			(hide yes)
			(effects
				(font
					(size 1.016 1.016)
					(thickness 0.1524)
				)
				(justify mirror)
			)
		)
		(duplicate_pad_numbers_are_jumpers no)
		(fp_rect
			(start 0.2794 0.6477)
			(end -0.2794 -0.6477)
			(stroke
				(width 0)
				(type default)
			)
			(fill no)
			(layer "B.CrtYd")
		)
		(fp_rect
			(start 0.2794 0.6477)
			(end -0.2794 -0.6477)
			(stroke
				(width 0)
				(type default)
			)
			(fill no)
			(layer "B.Fab")
		)
		(pad "1" smd custom
			(at 0 -0.2794 180)
			(size 0.0762 0.0762)
			(layers "B.Cu" "B.Mask" "B.Paste")
			(net "GB_VDDA")
			(options
				(clearance outline)
				(anchor circle)
			)
			(primitives
				(gr_poly
					(pts
						(arc
							(start 0.1524 0.127)
							(mid 0.137521 0.162921)
							(end 0.1016 0.1778)
						)
						(arc
							(start -0.1016 0.1778)
							(mid -0.137521 0.162921)
							(end -0.1524 0.127)
						)
						(arc
							(start -0.1524 -0.127)
							(mid -0.137521 -0.162921)
							(end -0.1016 -0.1778)
						)
						(arc
							(start 0.1016 -0.1778)
							(mid 0.137521 -0.162921)
							(end 0.1524 -0.127)
						)
					)
					(width 0)
					(fill yes)
				)
			)
		)
		(pad "2" smd custom
			(at 0 0.2794 180)
			(size 0.0762 0.0762)
			(layers "B.Cu" "B.Mask" "B.Paste")
			(net "GND")
			(options
				(clearance outline)
				(anchor circle)
			)
			(primitives
				(gr_poly
					(pts
						(arc
							(start 0.1524 0.127)
							(mid 0.137521 0.162921)
							(end 0.1016 0.1778)
						)
						(arc
							(start -0.1016 0.1778)
							(mid -0.137521 0.162921)
							(end -0.1524 0.127)
						)
						(arc
							(start -0.1524 -0.127)
							(mid -0.137521 -0.162921)
							(end -0.1016 -0.1778)
						)
						(arc
							(start 0.1016 -0.1778)
							(mid 0.137521 -0.162921)
							(end 0.1524 -0.127)
						)
					)
					(width 0)
					(fill yes)
				)
			)
		)
	)
	(footprint ""
		(layer "B.Cu")
		(at 113.570766 -39.878)
		(property "Reference" "STP22"
			(at 0 0 0)
			(layer "B.SilkS")
			(hide yes)
			(effects
				(font
					(size 1.27 1.27)
				)
				(justify mirror)
			)
		)
		(property "Value" "TPAD28"
			(at -0.0127 -1.8034 0)
			(unlocked yes)
			(layer "B.Fab")
			(hide yes)
			(effects
				(font
					(size 1.016 1.016)
					(thickness 0.1524)
				)
				(justify mirror)
			)
		)
		(property "Device Type" "TPAD28"
			(at -0.0127 -3.3274 0)
			(unlocked yes)
			(layer "B.Fab")
			(hide yes)
			(effects
				(font
					(size 1.016 1.016)
					(thickness 0.1524)
				)
				(justify mirror)
			)
		)
		(duplicate_pad_numbers_are_jumpers no)
		(fp_poly
			(pts
				(arc
					(start 0.3556 0)
					(mid -0.3556 0)
					(end 0.3556 0)
				)
			)
			(stroke
				(width 0)
				(type default)
			)
			(fill no)
			(layer "B.CrtYd")
		)
		(fp_poly
			(pts
				(arc
					(start 0.6096 0)
					(mid -0.6096 0)
					(end 0.6096 0)
				)
			)
			(stroke
				(width 0)
				(type default)
			)
			(fill no)
			(layer "B.Fab")
		)
		(pad "1" smd circle
			(at 0 0 180)
			(size 0.7112 0.7112)
			(layers "B.Cu" "B.Mask" "B.Paste")
			(net "IOC_GPIO_36")
		)
	)
	(footprint ""
		(layer "B.Cu")
		(at 51.76393 -76.761086)
		(property "Reference" "SC1279"
			(at 0 0 0)
			(layer "B.SilkS")
			(hide yes)
			(effects
				(font
					(size 1.27 1.27)
				)
				(justify mirror)
			)
		)
		(property "Value" "SCD01U50V2KX-1GP"
			(at -1.1811 -2.7051 0)
			(unlocked yes)
			(layer "B.Fab")
			(hide yes)
			(effects
				(font
					(size 1.016 1.016)
					(thickness 0.1524)
				)
				(justify mirror)
			)
		)
		(property "Device Type" "C402H22"
			(at -1.1811 -4.2291 0)
			(unlocked yes)
			(layer "B.Fab")
			(hide yes)
			(effects
				(font
					(size 1.016 1.016)
					(thickness 0.1524)
				)
				(justify mirror)
			)
		)
		(duplicate_pad_numbers_are_jumpers no)
		(fp_rect
			(start 0.4318 0.9525)
			(end -0.4318 -0.9525)
			(stroke
				(width 0)
				(type default)
			)
			(fill no)
			(layer "B.CrtYd")
		)
		(fp_rect
			(start 0.4318 0.9525)
			(end -0.4318 -0.9525)
			(stroke
				(width 0)
				(type default)
			)
			(fill no)
			(layer "B.Fab")
		)
		(pad "1" smd custom
			(at 0 -0.4445 180)
			(size 0.1524 0.1524)
			(layers "B.Cu" "B.Mask" "B.Paste")
			(net "SAS_EXP2CONN_RX_N_22")
			(options
				(clearance outline)
				(anchor circle)
			)
			(primitives
				(gr_poly
					(pts
						(arc
							(start 0.3048 0.2032)
							(mid 0.275042 0.275042)
							(end 0.2032 0.3048)
						)
						(arc
							(start -0.2032 0.3048)
							(mid -0.275042 0.275042)
							(end -0.3048 0.2032)
						)
						(arc
							(start -0.3048 -0.2032)
							(mid -0.275042 -0.275042)
							(end -0.2032 -0.3048)
						)
						(arc
							(start 0.2032 -0.3048)
							(mid 0.275042 -0.275042)
							(end 0.3048 -0.2032)
						)
					)
					(width 0)
					(fill yes)
				)
			)
		)
		(pad "2" smd custom
			(at 0 0.4445 180)
			(size 0.1524 0.1524)
			(layers "B.Cu" "B.Mask" "B.Paste")
			(net "MINI_RX_N_22")
			(options
				(clearance outline)
				(anchor circle)
			)
			(primitives
				(gr_poly
					(pts
						(arc
							(start 0.3048 0.2032)
							(mid 0.275042 0.275042)
							(end 0.2032 0.3048)
						)
						(arc
							(start -0.2032 0.3048)
							(mid -0.275042 0.275042)
							(end -0.3048 0.2032)
						)
						(arc
							(start -0.3048 -0.2032)
							(mid -0.275042 -0.275042)
							(end -0.2032 -0.3048)
						)
						(arc
							(start 0.2032 -0.3048)
							(mid 0.275042 -0.275042)
							(end 0.3048 -0.2032)
						)
					)
					(width 0)
					(fill yes)
				)
			)
		)
	)
	(footprint ""
		(layer "B.Cu")
		(at 108.312966 -49.784)
		(property "Reference" "TP260"
			(at 0 0 0)
			(layer "B.SilkS")
			(hide yes)
			(effects
				(font
					(size 1.27 1.27)
				)
				(justify mirror)
			)
		)
		(property "Value" "TPAD28"
			(at -0.0127 -1.8034 0)
			(unlocked yes)
			(layer "B.Fab")
			(hide yes)
			(effects
				(font
					(size 1.016 1.016)
					(thickness 0.1524)
				)
				(justify mirror)
			)
		)
		(property "Device Type" "TPAD28"
			(at -0.0127 -3.3274 0)
			(unlocked yes)
			(layer "B.Fab")
			(hide yes)
			(effects
				(font
					(size 1.016 1.016)
					(thickness 0.1524)
				)
				(justify mirror)
			)
		)
		(duplicate_pad_numbers_are_jumpers no)
		(fp_poly
			(pts
				(arc
					(start 0.3556 0)
					(mid -0.3556 0)
					(end 0.3556 0)
				)
			)
			(stroke
				(width 0)
				(type default)
			)
			(fill no)
			(layer "B.CrtYd")
		)
		(fp_poly
			(pts
				(arc
					(start 0.6096 0)
					(mid -0.6096 0)
					(end 0.6096 0)
				)
			)
			(stroke
				(width 0)
				(type default)
			)
			(fill no)
			(layer "B.Fab")
		)
		(pad "1" smd circle
			(at 0 0 180)
			(size 0.7112 0.7112)
			(layers "B.Cu" "B.Mask" "B.Paste")
			(net "VDDIO_15")
		)
	)
	(footprint ""
		(layer "B.Cu")
		(at 94.7928 -46.11116)
		(property "Reference" "SR667"
			(at 0 0 0)
			(layer "B.SilkS")
			(hide yes)
			(effects
				(font
					(size 1.27 1.27)
				)
				(justify mirror)
			)
		)
		(property "Value" "10KR2F-2-GP"
			(at -0.064008 -3.993896 0)
			(unlocked yes)
			(layer "B.Fab")
			(hide yes)
			(effects
				(font
					(size 1.016 1.016)
					(thickness 0.1524)
				)
				(justify mirror)
			)
		)
		(property "Device Type" "R402H16"
			(at -0.064008 -5.517896 0)
			(unlocked yes)
			(layer "B.Fab")
			(hide yes)
			(effects
				(font
					(size 1.016 1.016)
					(thickness 0.1524)
				)
				(justify mirror)
			)
		)
		(duplicate_pad_numbers_are_jumpers no)
		(fp_line
			(start -0.508 -0.9398)
			(end 0.508 -0.9398)
			(stroke
				(width 0.1524)
				(type default)
			)
			(layer "B.SilkS")
		)
		(fp_line
			(start 0.508 -0.9398)
			(end 0.508 0.9398)
			(stroke
				(width 0.1524)
				(type default)
			)
			(layer "B.SilkS")
		)
		(fp_rect
			(start 0.508 0.9398)
			(end -0.508 -0.9398)
			(stroke
				(width 0)
				(type default)
			)
			(fill no)
			(layer "B.CrtYd")
		)
		(fp_rect
			(start 0.508 0.9398)
			(end -0.508 -0.9398)
			(stroke
				(width 0)
				(type default)
			)
			(fill no)
			(layer "B.Fab")
		)
		(pad "1" smd custom
			(at 0 -0.4445 180)
			(size 0.1397 0.1397)
			(layers "B.Cu" "B.Mask" "B.Paste")
			(net "P1V8_C")
			(options
				(clearance outline)
				(anchor circle)
			)
			(primitives
				(gr_poly
					(pts
						(arc
							(start -0.1778 0.2794)
							(mid -0.249642 0.249642)
							(end -0.2794 0.1778)
						)
						(arc
							(start -0.2794 -0.1778)
							(mid -0.249642 -0.249642)
							(end -0.1778 -0.2794)
						)
						(arc
							(start 0.1778 -0.2794)
							(mid 0.249642 -0.249642)
							(end 0.2794 -0.1778)
						)
						(arc
							(start 0.2794 0.1778)
							(mid 0.249642 0.249642)
							(end 0.1778 0.2794)
						)
					)
					(width 0)
					(fill yes)
				)
			)
		)
		(pad "2" smd custom
			(at 0 0.4445 180)
			(size 0.1397 0.1397)
			(layers "B.Cu" "B.Mask" "B.Paste")
			(net "POWERLOSS#")
			(options
				(clearance outline)
				(anchor circle)
			)
			(primitives
				(gr_poly
					(pts
						(arc
							(start -0.1778 0.2794)
							(mid -0.249642 0.249642)
							(end -0.2794 0.1778)
						)
						(arc
							(start -0.2794 -0.1778)
							(mid -0.249642 -0.249642)
							(end -0.1778 -0.2794)
						)
						(arc
							(start 0.1778 -0.2794)
							(mid 0.249642 -0.249642)
							(end 0.2794 -0.1778)
						)
						(arc
							(start 0.2794 0.1778)
							(mid 0.249642 0.249642)
							(end 0.1778 0.2794)
						)
					)
					(width 0)
					(fill yes)
				)
			)
		)
	)
	(footprint ""
		(layer "B.Cu")
		(at 89.154 -100.203)
		(property "Reference" "SR822"
			(at 0 0 0)
			(layer "B.SilkS")
			(hide yes)
			(effects
				(font
					(size 1.27 1.27)
				)
				(justify mirror)
			)
		)
		(property "Value" "4K75R2F-1-GP"
			(at -0.064008 -3.993896 0)
			(unlocked yes)
			(layer "B.Fab")
			(hide yes)
			(effects
				(font
					(size 1.016 1.016)
					(thickness 0.1524)
				)
				(justify mirror)
			)
		)
		(property "Device Type" "R402H16"
			(at -0.064008 -5.517896 0)
			(unlocked yes)
			(layer "B.Fab")
			(hide yes)
			(effects
				(font
					(size 1.016 1.016)
					(thickness 0.1524)
				)
				(justify mirror)
			)
		)
		(duplicate_pad_numbers_are_jumpers no)
		(fp_line
			(start -0.508 -0.9398)
			(end 0.508 -0.9398)
			(stroke
				(width 0.1524)
				(type default)
			)
			(layer "B.SilkS")
		)
		(fp_line
			(start 0.508 -0.9398)
			(end 0.508 0.9398)
			(stroke
				(width 0.1524)
				(type default)
			)
			(layer "B.SilkS")
		)
		(fp_rect
			(start 0.508 0.9398)
			(end -0.508 -0.9398)
			(stroke
				(width 0)
				(type default)
			)
			(fill no)
			(layer "B.CrtYd")
		)
		(fp_rect
			(start 0.508 0.9398)
			(end -0.508 -0.9398)
			(stroke
				(width 0)
				(type default)
			)
			(fill no)
			(layer "B.Fab")
		)
		(pad "1" smd custom
			(at 0 -0.4445 180)
			(size 0.1397 0.1397)
			(layers "B.Cu" "B.Mask" "B.Paste")
			(net "EXP_FW_DET_BOARD_VER_1")
			(options
				(clearance outline)
				(anchor circle)
			)
			(primitives
				(gr_poly
					(pts
						(arc
							(start -0.1778 0.2794)
							(mid -0.249642 0.249642)
							(end -0.2794 0.1778)
						)
						(arc
							(start -0.2794 -0.1778)
							(mid -0.249642 -0.249642)
							(end -0.1778 -0.2794)
						)
						(arc
							(start 0.1778 -0.2794)
							(mid 0.249642 -0.249642)
							(end 0.2794 -0.1778)
						)
						(arc
							(start 0.2794 0.1778)
							(mid 0.249642 0.249642)
							(end 0.1778 0.2794)
						)
					)
					(width 0)
					(fill yes)
				)
			)
		)
		(pad "2" smd custom
			(at 0 0.4445 180)
			(size 0.1397 0.1397)
			(layers "B.Cu" "B.Mask" "B.Paste")
			(net "GND")
			(options
				(clearance outline)
				(anchor circle)
			)
			(primitives
				(gr_poly
					(pts
						(arc
							(start -0.1778 0.2794)
							(mid -0.249642 0.249642)
							(end -0.2794 0.1778)
						)
						(arc
							(start -0.2794 -0.1778)
							(mid -0.249642 -0.249642)
							(end -0.1778 -0.2794)
						)
						(arc
							(start 0.1778 -0.2794)
							(mid 0.249642 -0.249642)
							(end 0.2794 -0.1778)
						)
						(arc
							(start 0.2794 0.1778)
							(mid 0.249642 0.249642)
							(end 0.1778 0.2794)
						)
					)
					(width 0)
					(fill yes)
				)
			)
		)
	)
	(footprint ""
		(layer "B.Cu")
		(at 100.711 -82.677)
		(property "Reference" "SC1203"
			(at 0 0 0)
			(layer "B.SilkS")
			(hide yes)
			(effects
				(font
					(size 1.27 1.27)
				)
				(justify mirror)
			)
		)
		(property "Value" "SC10U6D3V5KX-4GP"
			(at 0.0762 -6.1214 0)
			(unlocked yes)
			(layer "B.Fab")
			(hide yes)
			(effects
				(font
					(size 1.016 1.016)
					(thickness 0.1524)
				)
				(justify mirror)
			)
		)
		(property "Device Type" "C805H58"
			(at 0.0762 -8.1534 0)
			(unlocked yes)
			(layer "B.Fab")
			(hide yes)
			(effects
				(font
					(size 1.016 1.016)
					(thickness 0.1524)
				)
				(justify mirror)
			)
		)
		(duplicate_pad_numbers_are_jumpers no)
		(fp_line
			(start -0.635 0)
			(end 0.635 0)
			(stroke
				(width 0.508)
				(type default)
			)
			(layer "B.SilkS")
		)
		(fp_rect
			(start 0.9652 1.778)
			(end -0.9652 -1.778)
			(stroke
				(width 0)
				(type default)
			)
			(fill no)
			(layer "B.CrtYd")
		)
		(fp_poly
			(pts
				(xy 0.9652 -1.778) (xy -0.9652 -1.778) (xy -0.9652 1.778) (xy 0.9652 1.778)
			)
			(stroke
				(width 0)
				(type default)
			)
			(fill no)
			(layer "B.Fab")
		)
		(pad "1" smd rect
			(at 0 -0.9652 180)
			(size 1.397 1.143)
			(layers "B.Cu" "B.Mask" "B.Paste")
			(net "P1V8_E")
		)
		(pad "2" smd rect
			(at 0 0.9652 180)
			(size 1.397 1.143)
			(layers "B.Cu" "B.Mask" "B.Paste")
			(net "GND")
		)
	)
	(footprint ""
		(layer "B.Cu")
		(at 117.856 -72.771 -90)
		(property "Reference" "SR957"
			(at 0 0 90)
			(layer "B.SilkS")
			(hide yes)
			(effects
				(font
					(size 1.27 1.27)
				)
				(justify mirror)
			)
		)
		(property "Value" "0R2J-2-GP"
			(at -0.064008 -3.993896 270)
			(unlocked yes)
			(layer "B.Fab")
			(hide yes)
			(effects
				(font
					(size 1.016 1.016)
					(thickness 0.1524)
				)
				(justify mirror)
			)
		)
		(property "Device Type" "R402H16"
			(at -0.064008 -5.517896 270)
			(unlocked yes)
			(layer "B.Fab")
			(hide yes)
			(effects
				(font
					(size 1.016 1.016)
					(thickness 0.1524)
				)
				(justify mirror)
			)
		)
		(duplicate_pad_numbers_are_jumpers no)
		(fp_line
			(start -0.508 -0.9398)
			(end 0.508 -0.9398)
			(stroke
				(width 0.1524)
				(type default)
			)
			(layer "B.SilkS")
		)
		(fp_line
			(start 0.508 -0.9398)
			(end 0.508 0.9398)
			(stroke
				(width 0.1524)
				(type default)
			)
			(layer "B.SilkS")
		)
		(fp_rect
			(start 0.508 0.9398)
			(end -0.508 -0.9398)
			(stroke
				(width 0)
				(type default)
			)
			(fill no)
			(layer "B.CrtYd")
		)
		(fp_rect
			(start 0.508 0.9398)
			(end -0.508 -0.9398)
			(stroke
				(width 0)
				(type default)
			)
			(fill no)
			(layer "B.Fab")
		)
		(pad "1" smd custom
			(at 0 -0.4445 90)
			(size 0.1397 0.1397)
			(layers "B.Cu" "B.Mask" "B.Paste")
			(net "SYS_RST_N_0")
			(options
				(clearance outline)
				(anchor circle)
			)
			(primitives
				(gr_poly
					(pts
						(arc
							(start -0.1778 0.2794)
							(mid -0.249642 0.249642)
							(end -0.2794 0.1778)
						)
						(arc
							(start -0.2794 -0.1778)
							(mid -0.249642 -0.249642)
							(end -0.1778 -0.2794)
						)
						(arc
							(start 0.1778 -0.2794)
							(mid 0.249642 -0.249642)
							(end 0.2794 -0.1778)
						)
						(arc
							(start 0.2794 0.1778)
							(mid 0.249642 0.249642)
							(end 0.1778 0.2794)
						)
					)
					(width 0)
					(fill yes)
				)
			)
		)
		(pad "2" smd custom
			(at 0 0.4445 90)
			(size 0.1397 0.1397)
			(layers "B.Cu" "B.Mask" "B.Paste")
			(net "EXP_LED_12")
			(options
				(clearance outline)
				(anchor circle)
			)
			(primitives
				(gr_poly
					(pts
						(arc
							(start -0.1778 0.2794)
							(mid -0.249642 0.249642)
							(end -0.2794 0.1778)
						)
						(arc
							(start -0.2794 -0.1778)
							(mid -0.249642 -0.249642)
							(end -0.1778 -0.2794)
						)
						(arc
							(start 0.1778 -0.2794)
							(mid 0.249642 -0.249642)
							(end 0.2794 -0.1778)
						)
						(arc
							(start 0.2794 0.1778)
							(mid 0.249642 0.249642)
							(end 0.1778 0.2794)
						)
					)
					(width 0)
					(fill yes)
				)
			)
		)
	)
)
